(kicad_pcb
	(version 20260206)
	(generator "pcbnew")
	(generator_version "10.0")
	(general
		(thickness 1.6)
		(legacy_teardrops no)
	)
	(paper "A4")
	(title_block
		(title "04192023_DAF0TMB3IC0_F0TG_MB_C_brd_V02_OCP.brd")
		(comment 1 "Grand Teton / footprints 7163-7168 of 8354")
	)
	(layers
		(0 "F.Cu" signal "TOP")
		(4 "In1.Cu" signal "GND")
		(6 "In2.Cu" signal "IN1")
		(8 "In3.Cu" signal "GND1")
		(10 "In4.Cu" signal "IN2")
		(12 "In5.Cu" signal "GND2")
		(14 "In6.Cu" signal "IN3")
		(16 "In7.Cu" signal "GND3")
		(18 "In8.Cu" signal "VCC")
		(20 "In9.Cu" signal "VCC1")
		(22 "In10.Cu" signal "GND4")
		(24 "In11.Cu" signal "IN4")
		(26 "In12.Cu" signal "GND5")
		(28 "In13.Cu" signal "IN5")
		(30 "In14.Cu" signal "GND6")
		(32 "In15.Cu" signal "IN6")
		(34 "In16.Cu" signal "GND7")
		(2 "B.Cu" signal "BOTTOM")
		(9 "F.Adhes" user "F.Adhesive")
		(11 "B.Adhes" user "B.Adhesive")
		(13 "F.Paste" user "Package Geometry/Pastemask Top")
		(15 "B.Paste" user "Package Geometry/Pastemask Bottom")
		(5 "F.SilkS" user "Ref Des/Silkscreen Top")
		(7 "B.SilkS" user "Ref Des/Silkscreen Bottom")
		(1 "F.Mask" user "Board Geometry/Soldermask Top")
		(3 "B.Mask" user "Board Geometry/Soldermask Bottom")
		(17 "Dwgs.User" user "User.Drawings")
		(19 "Cmts.User" user "User.Comments")
		(21 "Eco1.User" user "User.Eco1")
		(23 "Eco2.User" user "User.Eco2")
		(25 "Edge.Cuts" user "Board Geometry/Outline")
		(27 "Margin" user)
		(31 "F.CrtYd" user "Package Geometry/Place Bound Top")
		(29 "B.CrtYd" user "Package Geometry/Place Bound Bottom")
		(35 "F.Fab" user "Ref Des/Assembly Top")
		(33 "B.Fab" user "Ref Des/Assembly Bottom")
	)
	(footprint ""
		(layer "B.Cu")
		(at 185.458608 -116.642896 -90)
		(property "Reference" "C1173"
			(at 0 0 90)
			(layer "B.SilkS")
			(hide yes)
			(effects
				(font
					(size 1.27 1.27)
				)
				(justify mirror)
			)
		)
		(property "Value" ""
			(at 0 0 90)
			(layer "B.Fab")
			(effects
				(font
					(size 1.27 1.27)
				)
				(justify mirror)
			)
		)
		(duplicate_pad_numbers_are_jumpers no)
		(fp_line
			(start -0.69215 0.2921)
			(end 0.69215 0.2921)
			(stroke
				(width 0.1524)
				(type default)
			)
			(layer "B.SilkS")
		)
		(fp_line
			(start 0.69215 0.2921)
			(end 0.69215 -0.2921)
			(stroke
				(width 0.1524)
				(type default)
			)
			(layer "B.SilkS")
		)
		(fp_line
			(start -0.69215 -0.2921)
			(end -0.69215 0.2921)
			(stroke
				(width 0.1524)
				(type default)
			)
			(layer "B.SilkS")
		)
		(fp_line
			(start 0.69215 -0.2921)
			(end -0.69215 -0.2921)
			(stroke
				(width 0.1524)
				(type default)
			)
			(layer "B.SilkS")
		)
		(fp_line
			(start -0.51435 0.2794)
			(end 0.51435 0.2794)
			(stroke
				(width 0.1)
				(type default)
			)
			(layer "B.Fab")
		)
		(fp_line
			(start 0.51435 0.2794)
			(end 0.51435 -0.2794)
			(stroke
				(width 0.1)
				(type default)
			)
			(layer "B.Fab")
		)
		(fp_line
			(start -0.51435 -0.2794)
			(end -0.51435 0.2794)
			(stroke
				(width 0.1)
				(type default)
			)
			(layer "B.Fab")
		)
		(fp_line
			(start 0.51435 -0.2794)
			(end -0.51435 -0.2794)
			(stroke
				(width 0.1)
				(type default)
			)
			(layer "B.Fab")
		)
		(pad "1" smd circle
			(at 0.40005 0 90)
			(size 0 0)
			(layers "B.Cu" "B.Mask" "B.Paste")
			(net "P3V3_AUX")
		)
		(pad "2" smd circle
			(at -0.40005 0 90)
			(size 0 0)
			(layers "B.Cu" "B.Mask" "B.Paste")
			(net "GND")
		)
		(zone
			(layer "B.Cu")
			(hatch none 0.5)
			(connect_pads
				(clearance 0)
			)
			(min_thickness 0.25)
			(keepout
				(tracks not_allowed)
				(vias allowed)
				(pads allowed)
				(copperpour not_allowed)
				(footprints allowed)
			)
			(placement
				(enabled no)
				(sheetname "")
			)
			(fill
				(thermal_gap 0.5)
				(thermal_bridge_width 0.5)
				(island_removal_mode 0)
			)
			(polygon
				(pts
					(xy 185.312812 -116.543836) (xy 185.312812 -116.743226) (xy 185.370978 -116.833396) (xy 185.546238 -116.833396)
					(xy 185.604658 -116.743226) (xy 185.604658 -116.543836) (xy 185.546492 -116.452396) (xy 185.370978 -116.452396)
				)
			)
		)
	)
	(footprint ""
		(layer "B.Cu")
		(at 166.577518 -415.930588 180)
		(property "Reference" "R4575"
			(at 0 0 0)
			(layer "B.SilkS")
			(hide yes)
			(effects
				(font
					(size 1.27 1.27)
				)
				(justify mirror)
			)
		)
		(property "Value" ""
			(at 0 0 0)
			(layer "B.Fab")
			(effects
				(font
					(size 1.27 1.27)
				)
				(justify mirror)
			)
		)
		(duplicate_pad_numbers_are_jumpers no)
		(fp_line
			(start 0.7874 0.4064)
			(end 0.7874 -0.4064)
			(stroke
				(width 0.1524)
				(type default)
			)
			(layer "B.SilkS")
		)
		(fp_line
			(start 0.7874 -0.4064)
			(end -0.7874 -0.4064)
			(stroke
				(width 0.1524)
				(type default)
			)
			(layer "B.SilkS")
		)
		(fp_line
			(start -0.7874 0.4064)
			(end 0.7874 0.4064)
			(stroke
				(width 0.1524)
				(type default)
			)
			(layer "B.SilkS")
		)
		(fp_line
			(start -0.7874 -0.4064)
			(end -0.7874 0.4064)
			(stroke
				(width 0.1524)
				(type default)
			)
			(layer "B.SilkS")
		)
		(fp_line
			(start 0.67945 0.3048)
			(end 0.67945 -0.305054)
			(stroke
				(width 0.1)
				(type default)
			)
			(layer "B.Fab")
		)
		(fp_line
			(start 0.67945 -0.305054)
			(end 0.12065 -0.305054)
			(stroke
				(width 0.1)
				(type default)
			)
			(layer "B.Fab")
		)
		(fp_line
			(start 0.12065 0.3048)
			(end 0.67945 0.3048)
			(stroke
				(width 0.1)
				(type default)
			)
			(layer "B.Fab")
		)
		(fp_line
			(start 0.12065 0.2794)
			(end 0.12065 0.3048)
			(stroke
				(width 0.1)
				(type default)
			)
			(layer "B.Fab")
		)
		(fp_line
			(start 0.12065 -0.2794)
			(end -0.12065 -0.2794)
			(stroke
				(width 0.1)
				(type default)
			)
			(layer "B.Fab")
		)
		(fp_line
			(start 0.12065 -0.305054)
			(end 0.12065 -0.2794)
			(stroke
				(width 0.1)
				(type default)
			)
			(layer "B.Fab")
		)
		(fp_line
			(start -0.120396 0.3048)
			(end -0.120396 0.2794)
			(stroke
				(width 0.1)
				(type default)
			)
			(layer "B.Fab")
		)
		(fp_line
			(start -0.120396 0.2794)
			(end 0.12065 0.2794)
			(stroke
				(width 0.1)
				(type default)
			)
			(layer "B.Fab")
		)
		(fp_line
			(start -0.12065 -0.2794)
			(end -0.12065 -0.3048)
			(stroke
				(width 0.1)
				(type default)
			)
			(layer "B.Fab")
		)
		(fp_line
			(start -0.12065 -0.3048)
			(end -0.67945 -0.3048)
			(stroke
				(width 0.1)
				(type default)
			)
			(layer "B.Fab")
		)
		(fp_line
			(start -0.67945 0.3048)
			(end -0.120396 0.3048)
			(stroke
				(width 0.1)
				(type default)
			)
			(layer "B.Fab")
		)
		(fp_line
			(start -0.67945 -0.3048)
			(end -0.67945 0.3048)
			(stroke
				(width 0.1)
				(type default)
			)
			(layer "B.Fab")
		)
		(pad "1" smd circle
			(at 0.40005 0)
			(size 0 0)
			(layers "B.Cu" "B.Mask" "B.Paste")
			(net "GPU_3V3IO_RSVD0_FFU")
		)
		(pad "2" smd circle
			(at -0.40005 0)
			(size 0 0)
			(layers "B.Cu" "B.Mask" "B.Paste")
			(net "GPU_3V3IO_RSVD0_FFU_ISO")
		)
	)
	(footprint ""
		(layer "B.Cu")
		(at 96.719136 -390.560052 90)
		(property "Reference" "C331"
			(at 0 0 90)
			(layer "B.SilkS")
			(hide yes)
			(effects
				(font
					(size 1.27 1.27)
				)
				(justify mirror)
			)
		)
		(property "Value" ""
			(at 0 0 90)
			(layer "B.Fab")
			(effects
				(font
					(size 1.27 1.27)
				)
				(justify mirror)
			)
		)
		(duplicate_pad_numbers_are_jumpers no)
		(fp_line
			(start 0.7874 -0.4064)
			(end -0.7874 -0.4064)
			(stroke
				(width 0.1524)
				(type default)
			)
			(layer "B.SilkS")
		)
		(fp_line
			(start -0.7874 -0.4064)
			(end -0.7874 0.4064)
			(stroke
				(width 0.1524)
				(type default)
			)
			(layer "B.SilkS")
		)
		(fp_line
			(start 0.7874 0.4064)
			(end 0.7874 -0.4064)
			(stroke
				(width 0.1524)
				(type default)
			)
			(layer "B.SilkS")
		)
		(fp_line
			(start -0.7874 0.4064)
			(end 0.7874 0.4064)
			(stroke
				(width 0.1524)
				(type default)
			)
			(layer "B.SilkS")
		)
		(fp_line
			(start 0.67945 -0.305054)
			(end 0.12065 -0.305054)
			(stroke
				(width 0.1)
				(type default)
			)
			(layer "B.Fab")
		)
		(fp_line
			(start 0.12065 -0.305054)
			(end 0.12065 -0.2794)
			(stroke
				(width 0.1)
				(type default)
			)
			(layer "B.Fab")
		)
		(fp_line
			(start -0.12065 -0.3048)
			(end -0.67945 -0.3048)
			(stroke
				(width 0.1)
				(type default)
			)
			(layer "B.Fab")
		)
		(fp_line
			(start -0.67945 -0.3048)
			(end -0.67945 0.3048)
			(stroke
				(width 0.1)
				(type default)
			)
			(layer "B.Fab")
		)
		(fp_line
			(start 0.12065 -0.2794)
			(end -0.12065 -0.2794)
			(stroke
				(width 0.1)
				(type default)
			)
			(layer "B.Fab")
		)
		(fp_line
			(start -0.12065 -0.2794)
			(end -0.12065 -0.3048)
			(stroke
				(width 0.1)
				(type default)
			)
			(layer "B.Fab")
		)
		(fp_line
			(start 0.12065 0.2794)
			(end 0.12065 0.3048)
			(stroke
				(width 0.1)
				(type default)
			)
			(layer "B.Fab")
		)
		(fp_line
			(start -0.120396 0.2794)
			(end 0.12065 0.2794)
			(stroke
				(width 0.1)
				(type default)
			)
			(layer "B.Fab")
		)
		(fp_line
			(start 0.67945 0.3048)
			(end 0.67945 -0.305054)
			(stroke
				(width 0.1)
				(type default)
			)
			(layer "B.Fab")
		)
		(fp_line
			(start 0.12065 0.3048)
			(end 0.67945 0.3048)
			(stroke
				(width 0.1)
				(type default)
			)
			(layer "B.Fab")
		)
		(fp_line
			(start -0.120396 0.3048)
			(end -0.120396 0.2794)
			(stroke
				(width 0.1)
				(type default)
			)
			(layer "B.Fab")
		)
		(fp_line
			(start -0.67945 0.3048)
			(end -0.120396 0.3048)
			(stroke
				(width 0.1)
				(type default)
			)
			(layer "B.Fab")
		)
		(pad "1" smd circle
			(at 0.40005 0 270)
			(size 0 0)
			(layers "B.Cu" "B.Mask" "B.Paste")
			(net "P0V9_CPU1_RT1_2A")
		)
		(pad "2" smd circle
			(at -0.40005 0 270)
			(size 0 0)
			(layers "B.Cu" "B.Mask" "B.Paste")
			(net "GND")
		)
	)
	(footprint ""
		(layer "B.Cu")
		(at 172.727874 -193.996564)
		(property "Reference" "R111"
			(at 0 0 0)
			(layer "B.SilkS")
			(hide yes)
			(effects
				(font
					(size 1.27 1.27)
				)
				(justify mirror)
			)
		)
		(property "Value" ""
			(at 0 0 0)
			(layer "B.Fab")
			(effects
				(font
					(size 1.27 1.27)
				)
				(justify mirror)
			)
		)
		(duplicate_pad_numbers_are_jumpers no)
		(fp_line
			(start -0.7874 -0.4064)
			(end -0.7874 0.4064)
			(stroke
				(width 0.1524)
				(type default)
			)
			(layer "B.SilkS")
		)
		(fp_line
			(start -0.7874 0.4064)
			(end 0.7874 0.4064)
			(stroke
				(width 0.1524)
				(type default)
			)
			(layer "B.SilkS")
		)
		(fp_line
			(start 0.7874 -0.4064)
			(end -0.7874 -0.4064)
			(stroke
				(width 0.1524)
				(type default)
			)
			(layer "B.SilkS")
		)
		(fp_line
			(start 0.7874 0.4064)
			(end 0.7874 -0.4064)
			(stroke
				(width 0.1524)
				(type default)
			)
			(layer "B.SilkS")
		)
		(fp_line
			(start -0.67945 -0.3048)
			(end -0.67945 0.3048)
			(stroke
				(width 0.1)
				(type default)
			)
			(layer "B.Fab")
		)
		(fp_line
			(start -0.67945 0.3048)
			(end -0.120396 0.3048)
			(stroke
				(width 0.1)
				(type default)
			)
			(layer "B.Fab")
		)
		(fp_line
			(start -0.12065 -0.3048)
			(end -0.67945 -0.3048)
			(stroke
				(width 0.1)
				(type default)
			)
			(layer "B.Fab")
		)
		(fp_line
			(start -0.12065 -0.2794)
			(end -0.12065 -0.3048)
			(stroke
				(width 0.1)
				(type default)
			)
			(layer "B.Fab")
		)
		(fp_line
			(start -0.120396 0.2794)
			(end 0.12065 0.2794)
			(stroke
				(width 0.1)
				(type default)
			)
			(layer "B.Fab")
		)
		(fp_line
			(start -0.120396 0.3048)
			(end -0.120396 0.2794)
			(stroke
				(width 0.1)
				(type default)
			)
			(layer "B.Fab")
		)
		(fp_line
			(start 0.12065 -0.305054)
			(end 0.12065 -0.2794)
			(stroke
				(width 0.1)
				(type default)
			)
			(layer "B.Fab")
		)
		(fp_line
			(start 0.12065 -0.2794)
			(end -0.12065 -0.2794)
			(stroke
				(width 0.1)
				(type default)
			)
			(layer "B.Fab")
		)
		(fp_line
			(start 0.12065 0.2794)
			(end 0.12065 0.3048)
			(stroke
				(width 0.1)
				(type default)
			)
			(layer "B.Fab")
		)
		(fp_line
			(start 0.12065 0.3048)
			(end 0.67945 0.3048)
			(stroke
				(width 0.1)
				(type default)
			)
			(layer "B.Fab")
		)
		(fp_line
			(start 0.67945 -0.305054)
			(end 0.12065 -0.305054)
			(stroke
				(width 0.1)
				(type default)
			)
			(layer "B.Fab")
		)
		(fp_line
			(start 0.67945 0.3048)
			(end 0.67945 -0.305054)
			(stroke
				(width 0.1)
				(type default)
			)
			(layer "B.Fab")
		)
		(pad "1" smd circle
			(at 0.40005 0 180)
			(size 0 0)
			(layers "B.Cu" "B.Mask" "B.Paste")
			(net "P3V3")
		)
		(pad "2" smd circle
			(at -0.40005 0 180)
			(size 0 0)
			(layers "B.Cu" "B.Mask" "B.Paste")
			(net "PWRGD_CHH_CPU1_DIMM")
		)
	)
	(footprint ""
		(layer "B.Cu")
		(at 380.051056 -182.867554 -90)
		(property "Reference" "PC558_3"
			(at 0 0 90)
			(layer "B.SilkS")
			(hide yes)
			(effects
				(font
					(size 1.27 1.27)
				)
				(justify mirror)
			)
		)
		(property "Value" ""
			(at 0 0 90)
			(layer "B.Fab")
			(effects
				(font
					(size 1.27 1.27)
				)
				(justify mirror)
			)
		)
		(duplicate_pad_numbers_are_jumpers no)
		(fp_line
			(start -1.524 0.762)
			(end 1.524 0.762)
			(stroke
				(width 0.1524)
				(type default)
			)
			(layer "B.SilkS")
		)
		(fp_line
			(start 1.524 0.762)
			(end 1.524 -0.762)
			(stroke
				(width 0.1524)
				(type default)
			)
			(layer "B.SilkS")
		)
		(fp_line
			(start -1.524 -0.762)
			(end -1.524 0.762)
			(stroke
				(width 0.1524)
				(type default)
			)
			(layer "B.SilkS")
		)
		(fp_line
			(start 1.524 -0.762)
			(end -1.524 -0.762)
			(stroke
				(width 0.1524)
				(type default)
			)
			(layer "B.SilkS")
		)
		(fp_line
			(start -1.1049 0.724916)
			(end -1.1049 -0.724916)
			(stroke
				(width 0.1)
				(type default)
			)
			(layer "B.Fab")
		)
		(fp_line
			(start 1.1049 0.724916)
			(end -1.1049 0.724916)
			(stroke
				(width 0.1)
				(type default)
			)
			(layer "B.Fab")
		)
		(fp_line
			(start -1.1049 -0.724916)
			(end 1.1049 -0.724916)
			(stroke
				(width 0.1)
				(type default)
			)
			(layer "B.Fab")
		)
		(fp_line
			(start 1.1049 -0.724916)
			(end 1.1049 0.724916)
			(stroke
				(width 0.1)
				(type default)
			)
			(layer "B.Fab")
		)
		(pad "1" smd rect
			(at 0.889 0 270)
			(size 1.016 1.27)
			(layers "B.Cu" "B.Mask" "B.Paste")
			(net "SW_P12V_AUX_PVDDCR_CPU0_P0_FLT")
		)
		(pad "2" smd rect
			(at -0.889 0 270)
			(size 1.016 1.27)
			(layers "B.Cu" "B.Mask" "B.Paste")
			(net "GND")
		)
	)
	(footprint ""
		(layer "B.Cu")
		(at 442.345826 -399.56359 -90)
		(property "Reference" "PR6552"
			(at 0 0 90)
			(layer "B.SilkS")
			(hide yes)
			(effects
				(font
					(size 1.27 1.27)
				)
				(justify mirror)
			)
		)
		(property "Value" ""
			(at 0 0 90)
			(layer "B.Fab")
			(effects
				(font
					(size 1.27 1.27)
				)
				(justify mirror)
			)
		)
		(duplicate_pad_numbers_are_jumpers no)
		(fp_line
			(start -0.7874 0.4064)
			(end 0.7874 0.4064)
			(stroke
				(width 0.1524)
				(type default)
			)
			(layer "B.SilkS")
		)
		(fp_line
			(start 0.7874 0.4064)
			(end 0.7874 -0.4064)
			(stroke
				(width 0.1524)
				(type default)
			)
			(layer "B.SilkS")
		)
		(fp_line
			(start -0.7874 -0.4064)
			(end -0.7874 0.4064)
			(stroke
				(width 0.1524)
				(type default)
			)
			(layer "B.SilkS")
		)
		(fp_line
			(start 0.7874 -0.4064)
			(end -0.7874 -0.4064)
			(stroke
				(width 0.1524)
				(type default)
			)
			(layer "B.SilkS")
		)
		(fp_line
			(start -0.67945 0.3048)
			(end -0.120396 0.3048)
			(stroke
				(width 0.1)
				(type default)
			)
			(layer "B.Fab")
		)
		(fp_line
			(start -0.120396 0.3048)
			(end -0.120396 0.2794)
			(stroke
				(width 0.1)
				(type default)
			)
			(layer "B.Fab")
		)
		(fp_line
			(start 0.12065 0.3048)
			(end 0.67945 0.3048)
			(stroke
				(width 0.1)
				(type default)
			)
			(layer "B.Fab")
		)
		(fp_line
			(start 0.67945 0.3048)
			(end 0.67945 -0.305054)
			(stroke
				(width 0.1)
				(type default)
			)
			(layer "B.Fab")
		)
		(fp_line
			(start -0.120396 0.2794)
			(end 0.12065 0.2794)
			(stroke
				(width 0.1)
				(type default)
			)
			(layer "B.Fab")
		)
		(fp_line
			(start 0.12065 0.2794)
			(end 0.12065 0.3048)
			(stroke
				(width 0.1)
				(type default)
			)
			(layer "B.Fab")
		)
		(fp_line
			(start -0.12065 -0.2794)
			(end -0.12065 -0.3048)
			(stroke
				(width 0.1)
				(type default)
			)
			(layer "B.Fab")
		)
		(fp_line
			(start 0.12065 -0.2794)
			(end -0.12065 -0.2794)
			(stroke
				(width 0.1)
				(type default)
			)
			(layer "B.Fab")
		)
		(fp_line
			(start -0.67945 -0.3048)
			(end -0.67945 0.3048)
			(stroke
				(width 0.1)
				(type default)
			)
			(layer "B.Fab")
		)
		(fp_line
			(start -0.12065 -0.3048)
			(end -0.67945 -0.3048)
			(stroke
				(width 0.1)
				(type default)
			)
			(layer "B.Fab")
		)
		(fp_line
			(start 0.12065 -0.305054)
			(end 0.12065 -0.2794)
			(stroke
				(width 0.1)
				(type default)
			)
			(layer "B.Fab")
		)
		(fp_line
			(start 0.67945 -0.305054)
			(end 0.12065 -0.305054)
			(stroke
				(width 0.1)
				(type default)
			)
			(layer "B.Fab")
		)
		(pad "1" smd circle
			(at 0.40005 0 90)
			(size 0 0)
			(layers "B.Cu" "B.Mask" "B.Paste")
			(net "P0V9_RETIMER_CPU0_PVCC")
		)
		(pad "2" smd circle
			(at -0.40005 0 90)
			(size 0 0)
			(layers "B.Cu" "B.Mask" "B.Paste")
			(net "P0V9_RETIMER_CPU0_VCC1")
		)
	)
)
